#ISCELL
  pure_quanta quanta_title_block_c *
  *
#ISCELL
  standard offpage *
  page234_i1
#CELL
  pure_quanta q_res *
  page234_i10
#ISCELL
  logical_power universal_power *
  page234_i11
#CELL
  pure_quanta mosfet_nch_gds_esd_protected *
  page234_i14
#ISCELL
  logical_power universal_gnd *
  page234_i15
#CELL
  pure_quanta q_res *
  page234_i3
#ISCELL
  logical_power universal_gnd *
  page234_i5
#CELL
  pure_quanta mosfet_nch_gds_esd_protected *
  page234_i6
#CELL
  pure_quanta q_res *
  page234_i7
#CELL
  pure_quanta q_res *
  page234_i8
#ISCELL
  logical_power universal_power *
  page234_i9
